(kicad_pcb
	(version 20260206)
	(generator "pcbnew")
	(generator_version "10.0")
	(general
		(thickness 1.6)
		(legacy_teardrops no)
	)
	(paper "A4")
	(title_block
		(title "dpb — 14545-sa.0730WZS0815.brd")
		(comment 1 "Honey Badger (Wiwynn) / footprints 837-841 of 1066")
	)
	(layers
		(0 "F.Cu" signal "TOP")
		(4 "In1.Cu" signal "L2GND")
		(6 "In2.Cu" signal "L3")
		(8 "In3.Cu" signal "L4VCC")
		(10 "In4.Cu" signal "L5VCC")
		(12 "In5.Cu" signal "L6")
		(14 "In6.Cu" signal "L7GND")
		(2 "B.Cu" signal "BOTTOM")
		(9 "F.Adhes" user "F.Adhesive")
		(11 "B.Adhes" user "B.Adhesive")
		(13 "F.Paste" user "Package Geometry/Pastemask Top")
		(15 "B.Paste" user "Package Geometry/Pastemask Bottom")
		(5 "F.SilkS" user "Ref Des/Silkscreen Top")
		(7 "B.SilkS" user "Ref Des/Silkscreen Bottom")
		(1 "F.Mask" user "Board Geometry/Soldermask Top")
		(3 "B.Mask" user "Board Geometry/Soldermask Bottom")
		(17 "Dwgs.User" user "User.Drawings")
		(19 "Cmts.User" user "User.Comments")
		(21 "Eco1.User" user "User.Eco1")
		(23 "Eco2.User" user "User.Eco2")
		(25 "Edge.Cuts" user "Board Geometry/Outline")
		(27 "Margin" user)
		(31 "F.CrtYd" user "Package Geometry/Place Bound Top")
		(29 "B.CrtYd" user "Package Geometry/Place Bound Bottom")
		(35 "F.Fab" user "Ref Des/Assembly Top")
		(33 "B.Fab" user "Ref Des/Assembly Bottom")
	)
	(footprint ""
		(layer "F.Cu")
		(at 6.86562 -489.442252)
		(property "Reference" "PR47"
			(at 0 0 0)
			(layer "F.SilkS")
			(hide yes)
			(effects
				(font
					(size 1.27 1.27)
				)
			)
		)
		(property "Value" "76K8R2F-GP"
			(at 0.064008 -3.993896 0)
			(unlocked yes)
			(layer "F.Fab")
			(hide yes)
			(effects
				(font
					(size 1.016 1.016)
					(thickness 0.1524)
				)
			)
		)
		(property "Device Type" "R402H16"
			(at 0.064008 -5.517896 0)
			(unlocked yes)
			(layer "F.Fab")
			(hide yes)
			(effects
				(font
					(size 1.016 1.016)
					(thickness 0.1524)
				)
			)
		)
		(duplicate_pad_numbers_are_jumpers no)
		(fp_line
			(start -0.508 -0.9398)
			(end -0.508 0.9398)
			(stroke
				(width 0.1524)
				(type default)
			)
			(layer "F.SilkS")
		)
		(fp_line
			(start 0.508 -0.9398)
			(end -0.508 -0.9398)
			(stroke
				(width 0.1524)
				(type default)
			)
			(layer "F.SilkS")
		)
		(fp_rect
			(start -0.508 0.9398)
			(end 0.508 -0.9398)
			(stroke
				(width 0)
				(type default)
			)
			(fill no)
			(layer "F.CrtYd")
		)
		(fp_rect
			(start -0.508 0.9398)
			(end 0.508 -0.9398)
			(stroke
				(width 0)
				(type default)
			)
			(fill no)
			(layer "F.Fab")
		)
		(pad "1" smd custom
			(at 0 -0.4445)
			(size 0.1397 0.1397)
			(layers "F.Cu" "F.Mask" "F.Paste")
			(net "P5VC_ROVP")
			(options
				(clearance outline)
				(anchor circle)
			)
			(primitives
				(gr_poly
					(pts
						(arc
							(start -0.1778 -0.2794)
							(mid -0.249642 -0.249642)
							(end -0.2794 -0.1778)
						)
						(arc
							(start -0.2794 0.1778)
							(mid -0.249642 0.249642)
							(end -0.1778 0.2794)
						)
						(arc
							(start 0.1778 0.2794)
							(mid 0.249642 0.249642)
							(end 0.2794 0.1778)
						)
						(arc
							(start 0.2794 -0.1778)
							(mid 0.249642 -0.249642)
							(end 0.1778 -0.2794)
						)
					)
					(width 0)
					(fill yes)
				)
			)
		)
		(pad "2" smd custom
			(at 0 0.4445)
			(size 0.1397 0.1397)
			(layers "F.Cu" "F.Mask" "F.Paste")
			(net "P5VC")
			(options
				(clearance outline)
				(anchor circle)
			)
			(primitives
				(gr_poly
					(pts
						(arc
							(start -0.1778 -0.2794)
							(mid -0.249642 -0.249642)
							(end -0.2794 -0.1778)
						)
						(arc
							(start -0.2794 0.1778)
							(mid -0.249642 0.249642)
							(end -0.1778 0.2794)
						)
						(arc
							(start 0.1778 0.2794)
							(mid 0.249642 0.249642)
							(end 0.2794 0.1778)
						)
						(arc
							(start 0.2794 -0.1778)
							(mid 0.249642 -0.249642)
							(end 0.1778 -0.2794)
						)
					)
					(width 0)
					(fill yes)
				)
			)
		)
	)
	(footprint ""
		(layer "F.Cu")
		(at 56.6166 -276.4282)
		(property "Reference" "C222"
			(at 0 0 0)
			(layer "F.SilkS")
			(hide yes)
			(effects
				(font
					(size 1.27 1.27)
				)
			)
		)
		(property "Value" "SCD01U50V2KX-1GP"
			(at 1.1811 -2.7051 0)
			(unlocked yes)
			(layer "F.Fab")
			(hide yes)
			(effects
				(font
					(size 1.016 1.016)
					(thickness 0.1524)
				)
			)
		)
		(property "Device Type" "C402H22"
			(at 1.1811 -4.2291 0)
			(unlocked yes)
			(layer "F.Fab")
			(hide yes)
			(effects
				(font
					(size 1.016 1.016)
					(thickness 0.1524)
				)
			)
		)
		(duplicate_pad_numbers_are_jumpers no)
		(fp_rect
			(start -0.4318 0.9525)
			(end 0.4318 -0.9525)
			(stroke
				(width 0)
				(type default)
			)
			(fill no)
			(layer "F.CrtYd")
		)
		(fp_rect
			(start -0.4318 0.9525)
			(end 0.4318 -0.9525)
			(stroke
				(width 0)
				(type default)
			)
			(fill no)
			(layer "F.Fab")
		)
		(pad "1" smd custom
			(at 0 -0.4445)
			(size 0.1524 0.1524)
			(layers "F.Cu" "F.Mask" "F.Paste")
			(net "HDD_PRSNT_NET7")
			(options
				(clearance outline)
				(anchor circle)
			)
			(primitives
				(gr_poly
					(pts
						(arc
							(start 0.3048 -0.2032)
							(mid 0.275042 -0.275042)
							(end 0.2032 -0.3048)
						)
						(arc
							(start -0.2032 -0.3048)
							(mid -0.275042 -0.275042)
							(end -0.3048 -0.2032)
						)
						(arc
							(start -0.3048 0.2032)
							(mid -0.275042 0.275042)
							(end -0.2032 0.3048)
						)
						(arc
							(start 0.2032 0.3048)
							(mid 0.275042 0.275042)
							(end 0.3048 0.2032)
						)
					)
					(width 0)
					(fill yes)
				)
			)
		)
		(pad "2" smd custom
			(at 0 0.4445)
			(size 0.1524 0.1524)
			(layers "F.Cu" "F.Mask" "F.Paste")
			(net "GND")
			(options
				(clearance outline)
				(anchor circle)
			)
			(primitives
				(gr_poly
					(pts
						(arc
							(start 0.3048 -0.2032)
							(mid 0.275042 -0.275042)
							(end 0.2032 -0.3048)
						)
						(arc
							(start -0.2032 -0.3048)
							(mid -0.275042 -0.275042)
							(end -0.3048 -0.2032)
						)
						(arc
							(start -0.3048 0.2032)
							(mid -0.275042 0.275042)
							(end -0.2032 0.3048)
						)
						(arc
							(start 0.2032 0.3048)
							(mid 0.275042 0.275042)
							(end 0.3048 0.2032)
						)
					)
					(width 0)
					(fill yes)
				)
			)
		)
	)
	(footprint ""
		(layer "F.Cu")
		(at 198.894446 -461.425036 180)
		(property "Reference" "C346"
			(at 0 0 180)
			(layer "F.SilkS")
			(hide yes)
			(effects
				(font
					(size 1.27 1.27)
				)
			)
		)
		(property "Value" "SC1U16V3KX-5GP"
			(at 0 -2.8194 180)
			(unlocked yes)
			(layer "F.Fab")
			(hide yes)
			(effects
				(font
					(size 1.016 1.016)
					(thickness 0.1524)
				)
			)
		)
		(property "Device Type" "C603H36"
			(at 0 -4.3434 180)
			(unlocked yes)
			(layer "F.Fab")
			(hide yes)
			(effects
				(font
					(size 1.016 1.016)
					(thickness 0.1524)
				)
			)
		)
		(duplicate_pad_numbers_are_jumpers no)
		(fp_line
			(start 0.508 0)
			(end -0.508 0)
			(stroke
				(width 0.2032)
				(type default)
			)
			(layer "F.SilkS")
		)
		(fp_rect
			(start -0.5842 1.3335)
			(end 0.5842 -1.3335)
			(stroke
				(width 0)
				(type default)
			)
			(fill no)
			(layer "F.CrtYd")
		)
		(fp_rect
			(start -0.5842 1.3335)
			(end 0.5842 -1.3335)
			(stroke
				(width 0)
				(type default)
			)
			(fill no)
			(layer "F.Fab")
		)
		(pad "1" smd custom
			(at 0 -0.762 180)
			(size 0.2159 0.2159)
			(layers "F.Cu" "F.Mask" "F.Paste")
			(net "P3V3")
			(options
				(clearance outline)
				(anchor circle)
			)
			(primitives
				(gr_poly
					(pts
						(arc
							(start -0.3302 -0.4318)
							(mid -0.402042 -0.402042)
							(end -0.4318 -0.3302)
						)
						(arc
							(start -0.4318 0.3302)
							(mid -0.402042 0.402042)
							(end -0.3302 0.4318)
						)
						(arc
							(start 0.3302 0.4318)
							(mid 0.402042 0.402042)
							(end 0.4318 0.3302)
						)
						(arc
							(start 0.4318 -0.3302)
							(mid 0.402042 -0.402042)
							(end 0.3302 -0.4318)
						)
					)
					(width 0)
					(fill yes)
				)
			)
		)
		(pad "2" smd custom
			(at 0 0.762 180)
			(size 0.2159 0.2159)
			(layers "F.Cu" "F.Mask" "F.Paste")
			(net "GND")
			(options
				(clearance outline)
				(anchor circle)
			)
			(primitives
				(gr_poly
					(pts
						(arc
							(start -0.3302 -0.4318)
							(mid -0.402042 -0.402042)
							(end -0.4318 -0.3302)
						)
						(arc
							(start -0.4318 0.3302)
							(mid -0.402042 0.402042)
							(end -0.3302 0.4318)
						)
						(arc
							(start 0.3302 0.4318)
							(mid 0.402042 0.402042)
							(end 0.4318 0.3302)
						)
						(arc
							(start 0.4318 -0.3302)
							(mid 0.402042 -0.402042)
							(end 0.3302 -0.4318)
						)
					)
					(width 0)
					(fill yes)
				)
			)
		)
	)
	(footprint ""
		(layer "F.Cu")
		(at 194.013582 -286.738568 -90)
		(property "Reference" "U9"
			(at 0 0 270)
			(layer "F.SilkS")
			(hide yes)
			(effects
				(font
					(size 1.27 1.27)
				)
			)
		)
		(property "Value" "74LVC1G08GW-1-GP"
			(at -2.3368 -8.6868 270)
			(unlocked yes)
			(layer "F.Fab")
			(hide yes)
			(effects
				(font
					(size 1.016 1.016)
					(thickness 0.1524)
				)
			)
		)
		(property "Device Type" "SC70-5H44"
			(at -2.3114 -10.414 270)
			(unlocked yes)
			(layer "F.Fab")
			(hide yes)
			(effects
				(font
					(size 1.016 1.016)
					(thickness 0.1524)
				)
			)
		)
		(duplicate_pad_numbers_are_jumpers no)
		(fp_line
			(start -1.27 1.7018)
			(end -1.27 -1.7018)
			(stroke
				(width 0.1524)
				(type default)
			)
			(layer "F.SilkS")
		)
		(fp_line
			(start 1.27 1.7018)
			(end -1.27 1.7018)
			(stroke
				(width 0.1524)
				(type default)
			)
			(layer "F.SilkS")
		)
		(fp_line
			(start -1.27 -1.7018)
			(end 1.27 -1.7018)
			(stroke
				(width 0.1524)
				(type default)
			)
			(layer "F.SilkS")
		)
		(fp_line
			(start 1.27 -1.7018)
			(end 1.27 1.7018)
			(stroke
				(width 0.1524)
				(type default)
			)
			(layer "F.SilkS")
		)
		(fp_line
			(start 0.6604 -1.8034)
			(end 1.3843 -1.8034)
			(stroke
				(width 0.3302)
				(type default)
			)
			(layer "F.SilkS")
		)
		(fp_line
			(start 1.3843 -1.8034)
			(end 1.3843 -1.1176)
			(stroke
				(width 0.3302)
				(type default)
			)
			(layer "F.SilkS")
		)
		(fp_rect
			(start -1.524 1.9558)
			(end 1.524 -1.9558)
			(stroke
				(width 0)
				(type default)
			)
			(fill no)
			(layer "F.CrtYd")
		)
		(fp_poly
			(pts
				(xy -1.524 -1.9558) (xy 1.524 -1.9558) (xy 1.524 1.9558) (xy -1.524 1.9558)
			)
			(stroke
				(width 0)
				(type default)
			)
			(fill no)
			(layer "F.Fab")
		)
		(pad "1" smd rect
			(at 0.65024 -0.8255 270)
			(size 0.4064 1.2192)
			(layers "F.Cu" "F.Mask" "F.Paste")
			(net "SAS_EXP_B_PWR2")
		)
		(pad "2" smd rect
			(at 0 -0.8255 270)
			(size 0.4064 1.2192)
			(layers "F.Cu" "F.Mask" "F.Paste")
			(net "SAS_EXP_A_PWR2")
		)
		(pad "3" smd rect
			(at -0.65024 -0.8255 270)
			(size 0.4064 1.2192)
			(layers "F.Cu" "F.Mask" "F.Paste")
			(net "GND")
		)
		(pad "4" smd rect
			(at -0.65024 0.8255 270)
			(size 0.4064 1.2192)
			(layers "F.Cu" "F.Mask" "F.Paste")
			(net "DRIVE_PWR2")
		)
		(pad "5" smd rect
			(at 0.65024 0.8255 270)
			(size 0.4064 1.2192)
			(layers "F.Cu" "F.Mask" "F.Paste")
			(net "P3V3")
		)
	)
	(footprint ""
		(layer "F.Cu")
		(at 208.914746 -42.4307 -90)
		(property "Reference" "R340"
			(at 0 0 270)
			(layer "F.SilkS")
			(hide yes)
			(effects
				(font
					(size 1.27 1.27)
				)
			)
		)
		(property "Value" "4K7R2J-2-GP"
			(at 0.064008 -3.993896 270)
			(unlocked yes)
			(layer "F.Fab")
			(hide yes)
			(effects
				(font
					(size 1.016 1.016)
					(thickness 0.1524)
				)
			)
		)
		(property "Device Type" "R402H16"
			(at 0.064008 -5.517896 270)
			(unlocked yes)
			(layer "F.Fab")
			(hide yes)
			(effects
				(font
					(size 1.016 1.016)
					(thickness 0.1524)
				)
			)
		)
		(duplicate_pad_numbers_are_jumpers no)
		(fp_line
			(start -0.508 -0.9398)
			(end -0.508 0.9398)
			(stroke
				(width 0.1524)
				(type default)
			)
			(layer "F.SilkS")
		)
		(fp_line
			(start 0.508 -0.9398)
			(end -0.508 -0.9398)
			(stroke
				(width 0.1524)
				(type default)
			)
			(layer "F.SilkS")
		)
		(fp_rect
			(start -0.508 0.9398)
			(end 0.508 -0.9398)
			(stroke
				(width 0)
				(type default)
			)
			(fill no)
			(layer "F.CrtYd")
		)
		(fp_rect
			(start -0.508 0.9398)
			(end 0.508 -0.9398)
			(stroke
				(width 0)
				(type default)
			)
			(fill no)
			(layer "F.Fab")
		)
		(pad "1" smd custom
			(at 0 -0.4445 270)
			(size 0.1397 0.1397)
			(layers "F.Cu" "F.Mask" "F.Paste")
			(net "I2C_B_TMP4_A1")
			(options
				(clearance outline)
				(anchor circle)
			)
			(primitives
				(gr_poly
					(pts
						(arc
							(start -0.1778 -0.2794)
							(mid -0.249642 -0.249642)
							(end -0.2794 -0.1778)
						)
						(arc
							(start -0.2794 0.1778)
							(mid -0.249642 0.249642)
							(end -0.1778 0.2794)
						)
						(arc
							(start 0.1778 0.2794)
							(mid 0.249642 0.249642)
							(end 0.2794 0.1778)
						)
						(arc
							(start 0.2794 -0.1778)
							(mid 0.249642 -0.249642)
							(end 0.1778 -0.2794)
						)
					)
					(width 0)
					(fill yes)
				)
			)
		)
		(pad "2" smd custom
			(at 0 0.4445 270)
			(size 0.1397 0.1397)
			(layers "F.Cu" "F.Mask" "F.Paste")
			(net "GND")
			(options
				(clearance outline)
				(anchor circle)
			)
			(primitives
				(gr_poly
					(pts
						(arc
							(start -0.1778 -0.2794)
							(mid -0.249642 -0.249642)
							(end -0.2794 -0.1778)
						)
						(arc
							(start -0.2794 0.1778)
							(mid -0.249642 0.249642)
							(end -0.1778 0.2794)
						)
						(arc
							(start 0.1778 0.2794)
							(mid 0.249642 0.249642)
							(end 0.2794 0.1778)
						)
						(arc
							(start 0.2794 -0.1778)
							(mid 0.249642 -0.249642)
							(end 0.1778 -0.2794)
						)
					)
					(width 0)
					(fill yes)
				)
			)
		)
	)
)
